# BASEBOARD_FAB2 (Tioga Pass) — schematic netlist excerpt (pin names and nets, part order shuffled) for the footprints in the layout excerpt that follows; sources: Cadence DE-HDL packaged netlist, KiCad conversion of Wiwynn_Tioga_Pass_MB.brd

R8E24  RES  33.2 1% CHIP  pkg 0402  page 156 : A = IRQ_BMC_PCH_NMI_STBY_N ; B = IRQ_BMC_PCH_NMI_STBY_R_N
RT30  RES  0 5.0% CHIP  pkg 0603  page 219 : A = VR_PVDDQ_DEF_PH1_BOOT ; B = VR_PVDDQ_DEF_PH1_BOOT_R
L1D1  IND-120NH-30-GP  pkg DISCRET-GB2  page 208 : S = VR_PVCCIN_CPU1_PHASE4 ; F = PVCCIN_CPU1

(kicad_pcb
	(version 20260206)
	(generator "pcbnew")
	(generator_version "10.0")
	(general
		(thickness 1.6)
		(legacy_teardrops no)
	)
	(paper "A4")
	(title_block
		(title "Wiwynn_Tioga_Pass_MB.brd")
		(comment 1 "Tioga Pass / footprints 956-958 of 4770")
	)
	(layers
		(0 "F.Cu" signal "TOP")
		(4 "In1.Cu" signal "L2GND")
		(6 "In2.Cu" signal "L3")
		(8 "In3.Cu" signal "L4GND")
		(10 "In4.Cu" signal "L5")
		(12 "In5.Cu" signal "L6GND")
		(14 "In6.Cu" signal "L7VCC")
		(16 "In7.Cu" signal "L8VCC")
		(18 "In8.Cu" signal "L9GND")
		(20 "In9.Cu" signal "L10")
		(22 "In10.Cu" signal "L11GND")
		(24 "In11.Cu" signal "L12")
		(26 "In12.Cu" signal "L13GND")
		(2 "B.Cu" signal "BOTTOM")
		(9 "F.Adhes" user "F.Adhesive")
		(11 "B.Adhes" user "B.Adhesive")
		(13 "F.Paste" user "Package Geometry/Pastemask Top")
		(15 "B.Paste" user "Package Geometry/Pastemask Bottom")
		(5 "F.SilkS" user "Ref Des/Silkscreen Top")
		(7 "B.SilkS" user "Ref Des/Silkscreen Bottom")
		(1 "F.Mask" user "Board Geometry/Soldermask Top")
		(3 "B.Mask" user "Board Geometry/Soldermask Bottom")
		(17 "Dwgs.User" user "User.Drawings")
		(19 "Cmts.User" user "User.Comments")
		(21 "Eco1.User" user "User.Eco1")
		(23 "Eco2.User" user "User.Eco2")
		(25 "Edge.Cuts" user "Board Geometry/Outline")
		(27 "Margin" user)
		(31 "F.CrtYd" user "Package Geometry/Place Bound Top")
		(29 "B.CrtYd" user "Package Geometry/Place Bound Bottom")
		(35 "F.Fab" user "Ref Des/Assembly Top")
		(33 "B.Fab" user "Ref Des/Assembly Bottom")
	)
	(footprint ""
		(layer "F.Cu")
		(at 353.2505 -152.273 -90)
		(property "Reference" "RT30"
			(at 1.01473 0.656336 180)
			(unlocked yes)
			(layer "F.SilkS")
			(effects
				(font
					(size 0.4064 0.254)
					(thickness 0.1524)
				)
			)
		)
		(property "Value" ""
			(at 0 0 270)
			(layer "F.Fab")
			(effects
				(font
					(size 1.27 1.27)
				)
			)
		)
		(duplicate_pad_numbers_are_jumpers no)
		(fp_poly
			(pts
				(xy -0.4953 -0.2032) (xy 0.4953 -0.2032) (xy 0.4953 1.6002) (xy -0.4953 1.6002)
			)
			(stroke
				(width 0)
				(type default)
			)
			(fill no)
			(layer "F.CrtYd")
		)
		(fp_line
			(start -0.4953 1.6002)
			(end -0.4953 -0.2032)
			(stroke
				(width 0.1)
				(type default)
			)
			(layer "F.Fab")
		)
		(fp_line
			(start 0.4953 1.6002)
			(end -0.4953 1.6002)
			(stroke
				(width 0.1)
				(type default)
			)
			(layer "F.Fab")
		)
		(fp_line
			(start -0.4953 -0.2032)
			(end 0.4953 -0.2032)
			(stroke
				(width 0.1)
				(type default)
			)
			(layer "F.Fab")
		)
		(fp_line
			(start 0.4953 -0.2032)
			(end 0.4953 1.6002)
			(stroke
				(width 0.1)
				(type default)
			)
			(layer "F.Fab")
		)
		(pad "1" smd rect
			(at 0 0 270)
			(size 0.762 0.889)
			(layers "F.Cu" "F.Mask" "F.Paste")
			(net "VR_PVDDQ_DEF_PH1_BOOT")
		)
		(pad "2" smd rect
			(at 0 1.397 270)
			(size 0.762 0.889)
			(layers "F.Cu" "F.Mask" "F.Paste")
			(net "VR_PVDDQ_DEF_PH1_BOOT_R")
		)
		(zone
			(layer "F.Cu")
			(hatch none 0.5)
			(connect_pads
				(clearance 0)
			)
			(min_thickness 0.25)
			(keepout
				(tracks not_allowed)
				(vias allowed)
				(pads allowed)
				(copperpour not_allowed)
				(footprints allowed)
			)
			(placement
				(enabled no)
				(sheetname "")
			)
			(fill
				(thermal_gap 0.5)
				(thermal_bridge_width 0.5)
				(island_removal_mode 0)
			)
			(polygon
				(pts
					(xy 352.298 -152.654) (xy 352.298 -151.892) (xy 352.806 -151.892) (xy 352.806 -152.654)
				)
			)
		)
		(zone
			(layer "F.Cu")
			(hatch none 0.5)
			(connect_pads
				(clearance 0)
			)
			(min_thickness 0.25)
			(keepout
				(tracks allowed)
				(vias not_allowed)
				(pads allowed)
				(copperpour not_allowed)
				(footprints allowed)
			)
			(placement
				(enabled no)
				(sheetname "")
			)
			(fill
				(thermal_gap 0.5)
				(thermal_bridge_width 0.5)
				(island_removal_mode 0)
			)
			(polygon
				(pts
					(xy 352.298 -151.892) (xy 352.806 -151.892) (xy 352.806 -152.654) (xy 352.298 -152.654)
				)
			)
		)
	)
	(footprint ""
		(layer "F.Cu")
		(at 40.036496 -81.415382)
		(property "Reference" "L1D1"
			(at 3.378708 -4.251706 0)
			(unlocked yes)
			(layer "F.SilkS")
			(effects
				(font
					(size 0.4064 0.254)
					(thickness 0.1524)
				)
			)
		)
		(property "Value" ""
			(at 0 0 0)
			(layer "F.Fab")
			(effects
				(font
					(size 1.27 1.27)
				)
			)
		)
		(duplicate_pad_numbers_are_jumpers no)
		(fp_line
			(start -1.1303 -3.199892)
			(end 8.3693 -3.199892)
			(stroke
				(width 0.1524)
				(type default)
			)
			(layer "F.SilkS")
		)
		(fp_line
			(start -1.1303 -1.6637)
			(end -1.1303 -3.199892)
			(stroke
				(width 0.1524)
				(type default)
			)
			(layer "F.SilkS")
		)
		(fp_line
			(start -1.1303 3.199892)
			(end -1.1303 1.6637)
			(stroke
				(width 0.1524)
				(type default)
			)
			(layer "F.SilkS")
		)
		(fp_line
			(start 8.3693 -3.199892)
			(end 8.3693 -1.6637)
			(stroke
				(width 0.1524)
				(type default)
			)
			(layer "F.SilkS")
		)
		(fp_line
			(start 8.3693 1.6637)
			(end 8.3693 3.199892)
			(stroke
				(width 0.1524)
				(type default)
			)
			(layer "F.SilkS")
		)
		(fp_line
			(start 8.3693 3.199892)
			(end -1.1303 3.199892)
			(stroke
				(width 0.1524)
				(type default)
			)
			(layer "F.SilkS")
		)
		(fp_rect
			(start -1.1303 3.199892)
			(end 8.3693 -3.199892)
			(stroke
				(width 0)
				(type default)
			)
			(fill no)
			(layer "F.CrtYd")
		)
		(fp_line
			(start -1.1303 -3.199892)
			(end 8.3693 -3.199892)
			(stroke
				(width 0.1)
				(type default)
			)
			(layer "F.Fab")
		)
		(fp_line
			(start -1.1303 3.199892)
			(end -1.1303 -3.199892)
			(stroke
				(width 0.1)
				(type default)
			)
			(layer "F.Fab")
		)
		(fp_line
			(start 8.3693 -3.199892)
			(end 8.3693 3.199892)
			(stroke
				(width 0.1)
				(type default)
			)
			(layer "F.Fab")
		)
		(fp_line
			(start 8.3693 3.199892)
			(end -1.1303 3.199892)
			(stroke
				(width 0.1)
				(type default)
			)
			(layer "F.Fab")
		)
		(pad "1" smd rect
			(at 0 0)
			(size 3.683 2.667)
			(layers "F.Cu" "F.Mask" "F.Paste")
			(net "VR_PVCCIN_CPU1_PHASE4")
		)
		(pad "2" smd rect
			(at 7.239 0)
			(size 3.683 2.667)
			(layers "F.Cu" "F.Mask" "F.Paste")
			(net "PVCCIN_CPU1")
		)
	)
	(footprint ""
		(layer "F.Cu")
		(at 414.8455 -109.728 90)
		(property "Reference" "R8E24"
			(at 0 0 90)
			(layer "F.SilkS")
			(hide yes)
			(effects
				(font
					(size 1.27 1.27)
				)
			)
		)
		(property "Value" ""
			(at 0 0 90)
			(layer "F.Fab")
			(effects
				(font
					(size 1.27 1.27)
				)
			)
		)
		(duplicate_pad_numbers_are_jumpers no)
		(fp_poly
			(pts
				(xy -0.2794 -0.1016) (xy 0.2794 -0.1016) (xy 0.2794 0.9906) (xy -0.2794 0.9906)
			)
			(stroke
				(width 0)
				(type default)
			)
			(fill no)
			(layer "F.CrtYd")
		)
		(fp_line
			(start 0.2794 -0.1016)
			(end -0.2794 -0.1016)
			(stroke
				(width 0.1)
				(type default)
			)
			(layer "F.Fab")
		)
		(fp_line
			(start -0.2794 -0.1016)
			(end -0.2794 0.9906)
			(stroke
				(width 0.1)
				(type default)
			)
			(layer "F.Fab")
		)
		(fp_line
			(start 0.2794 0.9906)
			(end 0.2794 -0.1016)
			(stroke
				(width 0.1)
				(type default)
			)
			(layer "F.Fab")
		)
		(fp_line
			(start -0.2794 0.9906)
			(end 0.2794 0.9906)
			(stroke
				(width 0.1)
				(type default)
			)
			(layer "F.Fab")
		)
		(pad "1" smd rect
			(at 0 0 90)
			(size 0.508 0.508)
			(layers "F.Cu" "F.Mask" "F.Paste")
			(net "IRQ_BMC_PCH_NMI_STBY_N")
		)
		(pad "2" smd rect
			(at 0 0.889 90)
			(size 0.508 0.508)
			(layers "F.Cu" "F.Mask" "F.Paste")
			(net "IRQ_BMC_PCH_NMI_STBY_R_N")
		)
		(zone
			(layer "F.Cu")
			(hatch none 0.5)
			(connect_pads
				(clearance 0)
			)
			(min_thickness 0.25)
			(keepout
				(tracks allowed)
				(vias not_allowed)
				(pads allowed)
				(copperpour not_allowed)
				(footprints allowed)
			)
			(placement
				(enabled no)
				(sheetname "")
			)
			(fill
				(thermal_gap 0.5)
				(thermal_bridge_width 0.5)
				(island_removal_mode 0)
			)
			(polygon
				(pts
					(xy 415.0995 -109.474) (xy 415.0995 -109.982) (xy 415.4805 -109.982) (xy 415.4805 -109.474)
				)
			)
		)
		(zone
			(layer "F.Cu")
			(hatch none 0.5)
			(connect_pads
				(clearance 0)
			)
			(min_thickness 0.25)
			(keepout
				(tracks not_allowed)
				(vias allowed)
				(pads allowed)
				(copperpour not_allowed)
				(footprints allowed)
			)
			(placement
				(enabled no)
				(sheetname "")
			)
			(fill
				(thermal_gap 0.5)
				(thermal_bridge_width 0.5)
				(island_removal_mode 0)
			)
			(polygon
				(pts
					(xy 415.4805 -109.474) (xy 415.4805 -109.982) (xy 415.0995 -109.982) (xy 415.0995 -109.474)
				)
			)
		)
	)
)
